# T6G (Grand Teton) — schematic netlist excerpt (pin names and nets, part order shuffled) for the footprints in the layout excerpt that follows; sources: Cadence DE-HDL packaged netlist, KiCad conversion of 04192023_DAF0TMB3IC0_F0TG_MB_C_brd_V02_OCP.brd

R4154  Q_RES  100K 1% EMPTY  pkg 0402LF  page 125 : A = PRSNT_CABLE_GPU_A1_N ; B = GND
PR328  Q_RES  4.87K 1% EMPTY  pkg 0402LF  page 225 : A = GND ; B = PVDD11_S3_P1_LSET1

(kicad_pcb
	(version 20260206)
	(generator "pcbnew")
	(generator_version "10.0")
	(general
		(thickness 1.6)
		(legacy_teardrops no)
	)
	(paper "A4")
	(title_block
		(title "04192023_DAF0TMB3IC0_F0TG_MB_C_brd_V02_OCP.brd")
		(comment 1 "Grand Teton / footprints 275-276 of 8354")
	)
	(layers
		(0 "F.Cu" signal "TOP")
		(4 "In1.Cu" signal "GND")
		(6 "In2.Cu" signal "IN1")
		(8 "In3.Cu" signal "GND1")
		(10 "In4.Cu" signal "IN2")
		(12 "In5.Cu" signal "GND2")
		(14 "In6.Cu" signal "IN3")
		(16 "In7.Cu" signal "GND3")
		(18 "In8.Cu" signal "VCC")
		(20 "In9.Cu" signal "VCC1")
		(22 "In10.Cu" signal "GND4")
		(24 "In11.Cu" signal "IN4")
		(26 "In12.Cu" signal "GND5")
		(28 "In13.Cu" signal "IN5")
		(30 "In14.Cu" signal "GND6")
		(32 "In15.Cu" signal "IN6")
		(34 "In16.Cu" signal "GND7")
		(2 "B.Cu" signal "BOTTOM")
		(9 "F.Adhes" user "F.Adhesive")
		(11 "B.Adhes" user "B.Adhesive")
		(13 "F.Paste" user "Package Geometry/Pastemask Top")
		(15 "B.Paste" user "Package Geometry/Pastemask Bottom")
		(5 "F.SilkS" user "Ref Des/Silkscreen Top")
		(7 "B.SilkS" user "Ref Des/Silkscreen Bottom")
		(1 "F.Mask" user "Board Geometry/Soldermask Top")
		(3 "B.Mask" user "Board Geometry/Soldermask Bottom")
		(17 "Dwgs.User" user "User.Drawings")
		(19 "Cmts.User" user "User.Comments")
		(21 "Eco1.User" user "User.Eco1")
		(23 "Eco2.User" user "User.Eco2")
		(25 "Edge.Cuts" user "Board Geometry/Outline")
		(27 "Margin" user)
		(31 "F.CrtYd" user "Package Geometry/Place Bound Top")
		(29 "B.CrtYd" user "Package Geometry/Place Bound Bottom")
		(35 "F.Fab" user "Ref Des/Assembly Top")
		(33 "B.Fab" user "Ref Des/Assembly Bottom")
	)
	(footprint ""
		(layer "F.Cu")
		(at 355.506782 -412.030418 180)
		(property "Reference" "R4154"
			(at 0 0 180)
			(layer "F.SilkS")
			(hide yes)
			(effects
				(font
					(size 1.27 1.27)
				)
			)
		)
		(property "Value" ""
			(at 0 0 180)
			(layer "F.Fab")
			(effects
				(font
					(size 1.27 1.27)
				)
			)
		)
		(duplicate_pad_numbers_are_jumpers no)
		(fp_line
			(start 0.7874 0.4064)
			(end -0.7874 0.4064)
			(stroke
				(width 0.1524)
				(type default)
			)
			(layer "F.SilkS")
		)
		(fp_line
			(start 0.7874 -0.4064)
			(end 0.7874 0.4064)
			(stroke
				(width 0.1524)
				(type default)
			)
			(layer "F.SilkS")
		)
		(fp_line
			(start -0.7874 0.4064)
			(end -0.7874 -0.4064)
			(stroke
				(width 0.1524)
				(type default)
			)
			(layer "F.SilkS")
		)
		(fp_line
			(start -0.7874 -0.4064)
			(end 0.7874 -0.4064)
			(stroke
				(width 0.1524)
				(type default)
			)
			(layer "F.SilkS")
		)
		(fp_line
			(start 0.67945 0.3048)
			(end 0.120396 0.3048)
			(stroke
				(width 0.1)
				(type default)
			)
			(layer "F.Fab")
		)
		(fp_line
			(start 0.67945 -0.3048)
			(end 0.67945 0.3048)
			(stroke
				(width 0.1)
				(type default)
			)
			(layer "F.Fab")
		)
		(fp_line
			(start 0.12065 -0.2794)
			(end 0.12065 -0.3048)
			(stroke
				(width 0.1)
				(type default)
			)
			(layer "F.Fab")
		)
		(fp_line
			(start 0.12065 -0.3048)
			(end 0.67945 -0.3048)
			(stroke
				(width 0.1)
				(type default)
			)
			(layer "F.Fab")
		)
		(fp_line
			(start 0.120396 0.3048)
			(end 0.120396 0.2794)
			(stroke
				(width 0.1)
				(type default)
			)
			(layer "F.Fab")
		)
		(fp_line
			(start 0.120396 0.2794)
			(end -0.12065 0.2794)
			(stroke
				(width 0.1)
				(type default)
			)
			(layer "F.Fab")
		)
		(fp_line
			(start -0.12065 0.3048)
			(end -0.67945 0.3048)
			(stroke
				(width 0.1)
				(type default)
			)
			(layer "F.Fab")
		)
		(fp_line
			(start -0.12065 0.2794)
			(end -0.12065 0.3048)
			(stroke
				(width 0.1)
				(type default)
			)
			(layer "F.Fab")
		)
		(fp_line
			(start -0.12065 -0.2794)
			(end 0.12065 -0.2794)
			(stroke
				(width 0.1)
				(type default)
			)
			(layer "F.Fab")
		)
		(fp_line
			(start -0.12065 -0.305054)
			(end -0.12065 -0.2794)
			(stroke
				(width 0.1)
				(type default)
			)
			(layer "F.Fab")
		)
		(fp_line
			(start -0.67945 0.3048)
			(end -0.67945 -0.305054)
			(stroke
				(width 0.1)
				(type default)
			)
			(layer "F.Fab")
		)
		(fp_line
			(start -0.67945 -0.305054)
			(end -0.12065 -0.305054)
			(stroke
				(width 0.1)
				(type default)
			)
			(layer "F.Fab")
		)
		(pad "1" smd circle
			(at -0.40005 0 180)
			(size 0 0)
			(layers "F.Cu" "F.Mask" "F.Paste")
			(net "PRSNT_CABLE_GPU_A1_N")
		)
		(pad "2" smd circle
			(at 0.40005 0 180)
			(size 0 0)
			(layers "F.Cu" "F.Mask" "F.Paste")
			(net "GND")
		)
	)
	(footprint ""
		(layer "F.Cu")
		(at 181.615334 -356.507034 180)
		(property "Reference" "PR328"
			(at 0 0 180)
			(layer "F.SilkS")
			(hide yes)
			(effects
				(font
					(size 1.27 1.27)
				)
			)
		)
		(property "Value" ""
			(at 0 0 180)
			(layer "F.Fab")
			(effects
				(font
					(size 1.27 1.27)
				)
			)
		)
		(duplicate_pad_numbers_are_jumpers no)
		(fp_line
			(start 0.7874 0.4064)
			(end -0.7874 0.4064)
			(stroke
				(width 0.1524)
				(type default)
			)
			(layer "F.SilkS")
		)
		(fp_line
			(start 0.7874 -0.4064)
			(end 0.7874 0.4064)
			(stroke
				(width 0.1524)
				(type default)
			)
			(layer "F.SilkS")
		)
		(fp_line
			(start -0.7874 0.4064)
			(end -0.7874 -0.4064)
			(stroke
				(width 0.1524)
				(type default)
			)
			(layer "F.SilkS")
		)
		(fp_line
			(start -0.7874 -0.4064)
			(end 0.7874 -0.4064)
			(stroke
				(width 0.1524)
				(type default)
			)
			(layer "F.SilkS")
		)
		(fp_line
			(start 0.67945 0.3048)
			(end 0.120396 0.3048)
			(stroke
				(width 0.1)
				(type default)
			)
			(layer "F.Fab")
		)
		(fp_line
			(start 0.67945 -0.3048)
			(end 0.67945 0.3048)
			(stroke
				(width 0.1)
				(type default)
			)
			(layer "F.Fab")
		)
		(fp_line
			(start 0.12065 -0.2794)
			(end 0.12065 -0.3048)
			(stroke
				(width 0.1)
				(type default)
			)
			(layer "F.Fab")
		)
		(fp_line
			(start 0.12065 -0.3048)
			(end 0.67945 -0.3048)
			(stroke
				(width 0.1)
				(type default)
			)
			(layer "F.Fab")
		)
		(fp_line
			(start 0.120396 0.3048)
			(end 0.120396 0.2794)
			(stroke
				(width 0.1)
				(type default)
			)
			(layer "F.Fab")
		)
		(fp_line
			(start 0.120396 0.2794)
			(end -0.12065 0.2794)
			(stroke
				(width 0.1)
				(type default)
			)
			(layer "F.Fab")
		)
		(fp_line
			(start -0.12065 0.3048)
			(end -0.67945 0.3048)
			(stroke
				(width 0.1)
				(type default)
			)
			(layer "F.Fab")
		)
		(fp_line
			(start -0.12065 0.2794)
			(end -0.12065 0.3048)
			(stroke
				(width 0.1)
				(type default)
			)
			(layer "F.Fab")
		)
		(fp_line
			(start -0.12065 -0.2794)
			(end 0.12065 -0.2794)
			(stroke
				(width 0.1)
				(type default)
			)
			(layer "F.Fab")
		)
		(fp_line
			(start -0.12065 -0.305054)
			(end -0.12065 -0.2794)
			(stroke
				(width 0.1)
				(type default)
			)
			(layer "F.Fab")
		)
		(fp_line
			(start -0.67945 0.3048)
			(end -0.67945 -0.305054)
			(stroke
				(width 0.1)
				(type default)
			)
			(layer "F.Fab")
		)
		(fp_line
			(start -0.67945 -0.305054)
			(end -0.12065 -0.305054)
			(stroke
				(width 0.1)
				(type default)
			)
			(layer "F.Fab")
		)
		(pad "1" smd circle
			(at -0.40005 0 180)
			(size 0 0)
			(layers "F.Cu" "F.Mask" "F.Paste")
			(net "GND")
		)
		(pad "2" smd circle
			(at 0.40005 0 180)
			(size 0 0)
			(layers "F.Cu" "F.Mask" "F.Paste")
			(net "PVDD11_S3_P1_LSET1")
		)
	)
)
